# S9S_MB_2U (Grand Teton) — schematic netlist excerpt (pin names and nets, part order shuffled) for the footprints in the layout excerpt that follows; sources: Cadence DE-HDL packaged netlist, KiCad conversion of 03242023_DA0F0TMBIJ0_F0T_Motherboard_J_brd_V01_OCP.brd

R4634  Q_RES  1K 1% EMPTY  pkg 0402LF  page 248 : A = P3V3_AUX ; B = JTAG_BMC_SW_OE

Q76  MOSFET_NCH_DUAL  PJT138K IC  pkg SOT363XD  page 252
  S1  = GND
  G1  = PWRGD_P1V8_PCH_AUX
  D2  = LED_PWRGD_P1V05_PCH_AUX_D
  S2  = GND
  G2  = PWRGD_P1V05_PCH_AUX
  D1  = LED_PWRGD_P1V8_PCH_AUX_D

(kicad_pcb
	(version 20260206)
	(generator "pcbnew")
	(generator_version "10.0")
	(general
		(thickness 1.6)
		(legacy_teardrops no)
	)
	(paper "A4")
	(title_block
		(title "03242023_DA0F0TMBIJ0_F0T_Motherboard_J_brd_V01_OCP.brd")
		(comment 1 "Grand Teton / footprints 1523-1524 of 6105")
	)
	(layers
		(0 "F.Cu" signal "TOP")
		(4 "In1.Cu" signal "GND")
		(6 "In2.Cu" signal "IN1")
		(8 "In3.Cu" signal "GND1")
		(10 "In4.Cu" signal "IN2")
		(12 "In5.Cu" signal "GND2")
		(14 "In6.Cu" signal "IN3")
		(16 "In7.Cu" signal "GND3")
		(18 "In8.Cu" signal "VCC")
		(20 "In9.Cu" signal "VCC1")
		(22 "In10.Cu" signal "GND4")
		(24 "In11.Cu" signal "IN4")
		(26 "In12.Cu" signal "GND5")
		(28 "In13.Cu" signal "IN5")
		(30 "In14.Cu" signal "GND6")
		(32 "In15.Cu" signal "IN6")
		(34 "In16.Cu" signal "GND7")
		(2 "B.Cu" signal "BOTTOM")
		(9 "F.Adhes" user "F.Adhesive")
		(11 "B.Adhes" user "B.Adhesive")
		(13 "F.Paste" user "Package Geometry/Pastemask Top")
		(15 "B.Paste" user "Package Geometry/Pastemask Bottom")
		(5 "F.SilkS" user "Ref Des/Silkscreen Top")
		(7 "B.SilkS" user "Ref Des/Silkscreen Bottom")
		(1 "F.Mask" user "Board Geometry/Soldermask Top")
		(3 "B.Mask" user "Board Geometry/Soldermask Bottom")
		(17 "Dwgs.User" user "User.Drawings")
		(19 "Cmts.User" user "User.Comments")
		(21 "Eco1.User" user "User.Eco1")
		(23 "Eco2.User" user "User.Eco2")
		(25 "Edge.Cuts" user "Board Geometry/Outline")
		(27 "Margin" user)
		(31 "F.CrtYd" user "Package Geometry/Place Bound Top")
		(29 "B.CrtYd" user "Package Geometry/Place Bound Bottom")
		(35 "F.Fab" user "Ref Des/Assembly Top")
		(33 "B.Fab" user "Ref Des/Assembly Bottom")
	)
	(footprint ""
		(layer "F.Cu")
		(at 108.016802 -96.317054)
		(property "Reference" "Q76"
			(at 2.043938 -1.909064 0)
			(unlocked yes)
			(layer "F.SilkS")
			(effects
				(font
					(size 0.7874 0.5842)
					(thickness 0.1524)
				)
				(justify left)
			)
		)
		(property "Value" ""
			(at 0 0 0)
			(layer "F.Fab")
			(effects
				(font
					(size 1.27 1.27)
				)
			)
		)
		(duplicate_pad_numbers_are_jumpers no)
		(fp_line
			(start -1.332738 -1.100074)
			(end -0.4826 -1.100074)
			(stroke
				(width 0.1524)
				(type default)
			)
			(layer "F.SilkS")
		)
		(fp_line
			(start -1.332738 1.100074)
			(end -1.332738 -1.100074)
			(stroke
				(width 0.1524)
				(type default)
			)
			(layer "F.SilkS")
		)
		(fp_line
			(start -0.4826 -1.100074)
			(end 0 -0.541274)
			(stroke
				(width 0.1524)
				(type default)
			)
			(layer "F.SilkS")
		)
		(fp_line
			(start 0 -0.541274)
			(end 0.4826 -1.100074)
			(stroke
				(width 0.1524)
				(type default)
			)
			(layer "F.SilkS")
		)
		(fp_line
			(start 0.4826 -1.100074)
			(end 1.332738 -1.100074)
			(stroke
				(width 0.1524)
				(type default)
			)
			(layer "F.SilkS")
		)
		(fp_line
			(start 1.332738 -1.100074)
			(end 1.332738 1.100074)
			(stroke
				(width 0.1524)
				(type default)
			)
			(layer "F.SilkS")
		)
		(fp_line
			(start 1.332738 1.100074)
			(end -1.332738 1.100074)
			(stroke
				(width 0.1524)
				(type default)
			)
			(layer "F.SilkS")
		)
		(fp_poly
			(pts
				(xy -0.673862 -2.001012) (xy -1.02489 -1.298956) (xy -1.375918 -2.001012)
			)
			(stroke
				(width 0)
				(type default)
			)
			(fill yes)
			(layer "F.SilkS")
		)
		(fp_line
			(start -0.674878 -1.100074)
			(end 0.674878 -1.100074)
			(stroke
				(width 0.1)
				(type default)
			)
			(layer "F.Fab")
		)
		(fp_line
			(start -0.674878 1.100074)
			(end -0.674878 -1.100074)
			(stroke
				(width 0.1)
				(type default)
			)
			(layer "F.Fab")
		)
		(fp_line
			(start 0.674878 -1.100074)
			(end 0.674878 1.100074)
			(stroke
				(width 0.1)
				(type default)
			)
			(layer "F.Fab")
		)
		(fp_line
			(start 0.674878 1.100074)
			(end -0.674878 1.100074)
			(stroke
				(width 0.1)
				(type default)
			)
			(layer "F.Fab")
		)
		(fp_poly
			(pts
				(xy -2.2352 -0.298958) (xy -2.2352 -1.001014) (xy -1.533144 -0.649986)
			)
			(stroke
				(width 0)
				(type default)
			)
			(fill yes)
			(layer "F.Fab")
		)
		(pad "1" smd rect
			(at -0.94996 -0.649986 90)
			(size 0.4318 0.508)
			(layers "F.Cu" "F.Mask" "F.Paste")
			(net "GND")
		)
		(pad "2" smd rect
			(at -0.94996 0 90)
			(size 0.4318 0.508)
			(layers "F.Cu" "F.Mask" "F.Paste")
			(net "PWRGD_P1V8_PCH_AUX")
		)
		(pad "3" smd rect
			(at -0.94996 0.649986 90)
			(size 0.4318 0.508)
			(layers "F.Cu" "F.Mask" "F.Paste")
			(net "LED_PWRGD_P1V05_PCH_AUX_D")
		)
		(pad "4" smd rect
			(at 0.94996 0.649986 90)
			(size 0.4318 0.508)
			(layers "F.Cu" "F.Mask" "F.Paste")
			(net "GND")
		)
		(pad "5" smd rect
			(at 0.94996 0 90)
			(size 0.4318 0.508)
			(layers "F.Cu" "F.Mask" "F.Paste")
			(net "PWRGD_P1V05_PCH_AUX")
		)
		(pad "6" smd rect
			(at 0.94996 -0.649986 90)
			(size 0.4318 0.508)
			(layers "F.Cu" "F.Mask" "F.Paste")
			(net "LED_PWRGD_P1V8_PCH_AUX_D")
		)
	)
	(footprint ""
		(layer "F.Cu")
		(at 128.016 -61.432948 180)
		(property "Reference" "R4634"
			(at 0 0 180)
			(layer "F.SilkS")
			(hide yes)
			(effects
				(font
					(size 1.27 1.27)
				)
			)
		)
		(property "Value" ""
			(at 0 0 180)
			(layer "F.Fab")
			(effects
				(font
					(size 1.27 1.27)
				)
			)
		)
		(duplicate_pad_numbers_are_jumpers no)
		(fp_line
			(start 0.7874 0.4064)
			(end -0.7874 0.4064)
			(stroke
				(width 0.1524)
				(type default)
			)
			(layer "F.SilkS")
		)
		(fp_line
			(start 0.7874 -0.4064)
			(end 0.7874 0.4064)
			(stroke
				(width 0.1524)
				(type default)
			)
			(layer "F.SilkS")
		)
		(fp_line
			(start -0.7874 0.4064)
			(end -0.7874 -0.4064)
			(stroke
				(width 0.1524)
				(type default)
			)
			(layer "F.SilkS")
		)
		(fp_line
			(start -0.7874 -0.4064)
			(end 0.7874 -0.4064)
			(stroke
				(width 0.1524)
				(type default)
			)
			(layer "F.SilkS")
		)
		(fp_line
			(start 0.67945 0.3048)
			(end 0.120396 0.3048)
			(stroke
				(width 0.1)
				(type default)
			)
			(layer "F.Fab")
		)
		(fp_line
			(start 0.67945 -0.3048)
			(end 0.67945 0.3048)
			(stroke
				(width 0.1)
				(type default)
			)
			(layer "F.Fab")
		)
		(fp_line
			(start 0.12065 -0.2794)
			(end 0.12065 -0.3048)
			(stroke
				(width 0.1)
				(type default)
			)
			(layer "F.Fab")
		)
		(fp_line
			(start 0.12065 -0.3048)
			(end 0.67945 -0.3048)
			(stroke
				(width 0.1)
				(type default)
			)
			(layer "F.Fab")
		)
		(fp_line
			(start 0.120396 0.3048)
			(end 0.120396 0.2794)
			(stroke
				(width 0.1)
				(type default)
			)
			(layer "F.Fab")
		)
		(fp_line
			(start 0.120396 0.2794)
			(end -0.12065 0.2794)
			(stroke
				(width 0.1)
				(type default)
			)
			(layer "F.Fab")
		)
		(fp_line
			(start -0.12065 0.3048)
			(end -0.67945 0.3048)
			(stroke
				(width 0.1)
				(type default)
			)
			(layer "F.Fab")
		)
		(fp_line
			(start -0.12065 0.2794)
			(end -0.12065 0.3048)
			(stroke
				(width 0.1)
				(type default)
			)
			(layer "F.Fab")
		)
		(fp_line
			(start -0.12065 -0.2794)
			(end 0.12065 -0.2794)
			(stroke
				(width 0.1)
				(type default)
			)
			(layer "F.Fab")
		)
		(fp_line
			(start -0.12065 -0.305054)
			(end -0.12065 -0.2794)
			(stroke
				(width 0.1)
				(type default)
			)
			(layer "F.Fab")
		)
		(fp_line
			(start -0.67945 0.3048)
			(end -0.67945 -0.305054)
			(stroke
				(width 0.1)
				(type default)
			)
			(layer "F.Fab")
		)
		(fp_line
			(start -0.67945 -0.305054)
			(end -0.12065 -0.305054)
			(stroke
				(width 0.1)
				(type default)
			)
			(layer "F.Fab")
		)
		(pad "1" smd circle
			(at -0.40005 0 180)
			(size 0 0)
			(layers "F.Cu" "F.Mask" "F.Paste")
			(net "P3V3_AUX")
		)
		(pad "2" smd circle
			(at 0.40005 0 180)
			(size 0 0)
			(layers "F.Cu" "F.Mask" "F.Paste")
			(net "JTAG_BMC_SW_OE")
		)
	)
)
